# T6G (Grand Teton) — schematic netlist excerpt (pin names and nets, part order shuffled) for the footprints in the layout excerpt that follows; sources: Cadence DE-HDL packaged netlist, KiCad conversion of 04192023_DAF0TMB3IC0_F0TG_MB_C_brd_V02_OCP.brd

R217  Q_RES  33 5% CHIP  pkg 0402LF  page 81 : A = RST_CPU0_RSMRST_N ; B = FM_CPU0_RSMRST_N
C5020  Q_CAP  1000PF 50V 5% X7R  pkg 0402  page 217 : A = GND ; B = PVDDCR_CPU1_P1_SMB_ALERT

(kicad_pcb
	(version 20260206)
	(generator "pcbnew")
	(generator_version "10.0")
	(general
		(thickness 1.6)
		(legacy_teardrops no)
	)
	(paper "A4")
	(title_block
		(title "04192023_DAF0TMB3IC0_F0TG_MB_C_brd_V02_OCP.brd")
		(comment 1 "Grand Teton / footprints 2563-2564 of 8354")
	)
	(layers
		(0 "F.Cu" signal "TOP")
		(4 "In1.Cu" signal "GND")
		(6 "In2.Cu" signal "IN1")
		(8 "In3.Cu" signal "GND1")
		(10 "In4.Cu" signal "IN2")
		(12 "In5.Cu" signal "GND2")
		(14 "In6.Cu" signal "IN3")
		(16 "In7.Cu" signal "GND3")
		(18 "In8.Cu" signal "VCC")
		(20 "In9.Cu" signal "VCC1")
		(22 "In10.Cu" signal "GND4")
		(24 "In11.Cu" signal "IN4")
		(26 "In12.Cu" signal "GND5")
		(28 "In13.Cu" signal "IN5")
		(30 "In14.Cu" signal "GND6")
		(32 "In15.Cu" signal "IN6")
		(34 "In16.Cu" signal "GND7")
		(2 "B.Cu" signal "BOTTOM")
		(9 "F.Adhes" user "F.Adhesive")
		(11 "B.Adhes" user "B.Adhesive")
		(13 "F.Paste" user "Package Geometry/Pastemask Top")
		(15 "B.Paste" user "Package Geometry/Pastemask Bottom")
		(5 "F.SilkS" user "Ref Des/Silkscreen Top")
		(7 "B.SilkS" user "Ref Des/Silkscreen Bottom")
		(1 "F.Mask" user "Board Geometry/Soldermask Top")
		(3 "B.Mask" user "Board Geometry/Soldermask Bottom")
		(17 "Dwgs.User" user "User.Drawings")
		(19 "Cmts.User" user "User.Comments")
		(21 "Eco1.User" user "User.Eco1")
		(23 "Eco2.User" user "User.Eco2")
		(25 "Edge.Cuts" user "Board Geometry/Outline")
		(27 "Margin" user)
		(31 "F.CrtYd" user "Package Geometry/Place Bound Top")
		(29 "B.CrtYd" user "Package Geometry/Place Bound Bottom")
		(35 "F.Fab" user "Ref Des/Assembly Top")
		(33 "B.Fab" user "Ref Des/Assembly Bottom")
	)
	(footprint ""
		(layer "F.Cu")
		(at 22.479 -364.617 180)
		(property "Reference" "C5020"
			(at 0 0 180)
			(layer "F.SilkS")
			(hide yes)
			(effects
				(font
					(size 1.27 1.27)
				)
			)
		)
		(property "Value" ""
			(at 0 0 180)
			(layer "F.Fab")
			(effects
				(font
					(size 1.27 1.27)
				)
			)
		)
		(duplicate_pad_numbers_are_jumpers no)
		(fp_line
			(start 0.7874 0.4064)
			(end -0.7874 0.4064)
			(stroke
				(width 0.1524)
				(type default)
			)
			(layer "F.SilkS")
		)
		(fp_line
			(start 0.7874 -0.4064)
			(end 0.7874 0.4064)
			(stroke
				(width 0.1524)
				(type default)
			)
			(layer "F.SilkS")
		)
		(fp_line
			(start -0.7874 0.4064)
			(end -0.7874 -0.4064)
			(stroke
				(width 0.1524)
				(type default)
			)
			(layer "F.SilkS")
		)
		(fp_line
			(start -0.7874 -0.4064)
			(end 0.7874 -0.4064)
			(stroke
				(width 0.1524)
				(type default)
			)
			(layer "F.SilkS")
		)
		(fp_line
			(start 0.67945 0.3048)
			(end 0.120396 0.3048)
			(stroke
				(width 0.1)
				(type default)
			)
			(layer "F.Fab")
		)
		(fp_line
			(start 0.67945 -0.3048)
			(end 0.67945 0.3048)
			(stroke
				(width 0.1)
				(type default)
			)
			(layer "F.Fab")
		)
		(fp_line
			(start 0.12065 -0.2794)
			(end 0.12065 -0.3048)
			(stroke
				(width 0.1)
				(type default)
			)
			(layer "F.Fab")
		)
		(fp_line
			(start 0.12065 -0.3048)
			(end 0.67945 -0.3048)
			(stroke
				(width 0.1)
				(type default)
			)
			(layer "F.Fab")
		)
		(fp_line
			(start 0.120396 0.3048)
			(end 0.120396 0.2794)
			(stroke
				(width 0.1)
				(type default)
			)
			(layer "F.Fab")
		)
		(fp_line
			(start 0.120396 0.2794)
			(end -0.12065 0.2794)
			(stroke
				(width 0.1)
				(type default)
			)
			(layer "F.Fab")
		)
		(fp_line
			(start -0.12065 0.3048)
			(end -0.67945 0.3048)
			(stroke
				(width 0.1)
				(type default)
			)
			(layer "F.Fab")
		)
		(fp_line
			(start -0.12065 0.2794)
			(end -0.12065 0.3048)
			(stroke
				(width 0.1)
				(type default)
			)
			(layer "F.Fab")
		)
		(fp_line
			(start -0.12065 -0.2794)
			(end 0.12065 -0.2794)
			(stroke
				(width 0.1)
				(type default)
			)
			(layer "F.Fab")
		)
		(fp_line
			(start -0.12065 -0.305054)
			(end -0.12065 -0.2794)
			(stroke
				(width 0.1)
				(type default)
			)
			(layer "F.Fab")
		)
		(fp_line
			(start -0.67945 0.3048)
			(end -0.67945 -0.305054)
			(stroke
				(width 0.1)
				(type default)
			)
			(layer "F.Fab")
		)
		(fp_line
			(start -0.67945 -0.305054)
			(end -0.12065 -0.305054)
			(stroke
				(width 0.1)
				(type default)
			)
			(layer "F.Fab")
		)
		(pad "1" smd circle
			(at -0.40005 0 180)
			(size 0 0)
			(layers "F.Cu" "F.Mask" "F.Paste")
			(net "GND")
		)
		(pad "2" smd circle
			(at 0.40005 0 180)
			(size 0 0)
			(layers "F.Cu" "F.Mask" "F.Paste")
			(net "PVDDCR_CPU1_P1_SMB_ALERT")
		)
	)
	(footprint ""
		(layer "F.Cu")
		(at 180.970936 -133.235954 -90)
		(property "Reference" "R217"
			(at 0 0 270)
			(layer "F.SilkS")
			(hide yes)
			(effects
				(font
					(size 1.27 1.27)
				)
			)
		)
		(property "Value" ""
			(at 0 0 270)
			(layer "F.Fab")
			(effects
				(font
					(size 1.27 1.27)
				)
			)
		)
		(duplicate_pad_numbers_are_jumpers no)
		(fp_line
			(start -0.7874 0.4064)
			(end -0.7874 -0.4064)
			(stroke
				(width 0.1524)
				(type default)
			)
			(layer "F.SilkS")
		)
		(fp_line
			(start 0.7874 0.4064)
			(end -0.7874 0.4064)
			(stroke
				(width 0.1524)
				(type default)
			)
			(layer "F.SilkS")
		)
		(fp_line
			(start -0.7874 -0.4064)
			(end 0.7874 -0.4064)
			(stroke
				(width 0.1524)
				(type default)
			)
			(layer "F.SilkS")
		)
		(fp_line
			(start 0.7874 -0.4064)
			(end 0.7874 0.4064)
			(stroke
				(width 0.1524)
				(type default)
			)
			(layer "F.SilkS")
		)
		(fp_line
			(start -0.67945 0.3048)
			(end -0.67945 -0.305054)
			(stroke
				(width 0.1)
				(type default)
			)
			(layer "F.Fab")
		)
		(fp_line
			(start -0.12065 0.3048)
			(end -0.67945 0.3048)
			(stroke
				(width 0.1)
				(type default)
			)
			(layer "F.Fab")
		)
		(fp_line
			(start 0.120396 0.3048)
			(end 0.120396 0.2794)
			(stroke
				(width 0.1)
				(type default)
			)
			(layer "F.Fab")
		)
		(fp_line
			(start 0.67945 0.3048)
			(end 0.120396 0.3048)
			(stroke
				(width 0.1)
				(type default)
			)
			(layer "F.Fab")
		)
		(fp_line
			(start -0.12065 0.2794)
			(end -0.12065 0.3048)
			(stroke
				(width 0.1)
				(type default)
			)
			(layer "F.Fab")
		)
		(fp_line
			(start 0.120396 0.2794)
			(end -0.12065 0.2794)
			(stroke
				(width 0.1)
				(type default)
			)
			(layer "F.Fab")
		)
		(fp_line
			(start -0.12065 -0.2794)
			(end 0.12065 -0.2794)
			(stroke
				(width 0.1)
				(type default)
			)
			(layer "F.Fab")
		)
		(fp_line
			(start 0.12065 -0.2794)
			(end 0.12065 -0.3048)
			(stroke
				(width 0.1)
				(type default)
			)
			(layer "F.Fab")
		)
		(fp_line
			(start 0.12065 -0.3048)
			(end 0.67945 -0.3048)
			(stroke
				(width 0.1)
				(type default)
			)
			(layer "F.Fab")
		)
		(fp_line
			(start 0.67945 -0.3048)
			(end 0.67945 0.3048)
			(stroke
				(width 0.1)
				(type default)
			)
			(layer "F.Fab")
		)
		(fp_line
			(start -0.67945 -0.305054)
			(end -0.12065 -0.305054)
			(stroke
				(width 0.1)
				(type default)
			)
			(layer "F.Fab")
		)
		(fp_line
			(start -0.12065 -0.305054)
			(end -0.12065 -0.2794)
			(stroke
				(width 0.1)
				(type default)
			)
			(layer "F.Fab")
		)
		(pad "1" smd circle
			(at -0.40005 0 270)
			(size 0 0)
			(layers "F.Cu" "F.Mask" "F.Paste")
			(net "RST_CPU0_RSMRST_N")
		)
		(pad "2" smd circle
			(at 0.40005 0 270)
			(size 0 0)
			(layers "F.Cu" "F.Mask" "F.Paste")
			(net "FM_CPU0_RSMRST_N")
		)
	)
)
